# T6G (Grand Teton) — schematic netlist excerpt (pin names and nets, part order shuffled) for the footprints in the layout excerpt that follows; sources: Cadence DE-HDL packaged netlist, KiCad conversion of 04192023_DAF0TMB3IC0_F0TG_MB_C_brd_V02_OCP.brd

R6196  Q_RES  0 5% CHIP  pkg 0201LF  page 180 : A = USB2_CPU0_P0_HUB2_R_DP ; B = USB2_HUB_EXT_DP

(kicad_pcb
	(version 20260206)
	(generator "pcbnew")
	(generator_version "10.0")
	(general
		(thickness 1.6)
		(legacy_teardrops no)
	)
	(paper "A4")
	(title_block
		(title "04192023_DAF0TMB3IC0_F0TG_MB_C_brd_V02_OCP.brd")
		(comment 1 "Grand Teton / footprints 221-221 of 8354")
	)
	(layers
		(0 "F.Cu" signal "TOP")
		(4 "In1.Cu" signal "GND")
		(6 "In2.Cu" signal "IN1")
		(8 "In3.Cu" signal "GND1")
		(10 "In4.Cu" signal "IN2")
		(12 "In5.Cu" signal "GND2")
		(14 "In6.Cu" signal "IN3")
		(16 "In7.Cu" signal "GND3")
		(18 "In8.Cu" signal "VCC")
		(20 "In9.Cu" signal "VCC1")
		(22 "In10.Cu" signal "GND4")
		(24 "In11.Cu" signal "IN4")
		(26 "In12.Cu" signal "GND5")
		(28 "In13.Cu" signal "IN5")
		(30 "In14.Cu" signal "GND6")
		(32 "In15.Cu" signal "IN6")
		(34 "In16.Cu" signal "GND7")
		(2 "B.Cu" signal "BOTTOM")
		(9 "F.Adhes" user "F.Adhesive")
		(11 "B.Adhes" user "B.Adhesive")
		(13 "F.Paste" user "Package Geometry/Pastemask Top")
		(15 "B.Paste" user "Package Geometry/Pastemask Bottom")
		(5 "F.SilkS" user "Ref Des/Silkscreen Top")
		(7 "B.SilkS" user "Ref Des/Silkscreen Bottom")
		(1 "F.Mask" user "Board Geometry/Soldermask Top")
		(3 "B.Mask" user "Board Geometry/Soldermask Bottom")
		(17 "Dwgs.User" user "User.Drawings")
		(19 "Cmts.User" user "User.Comments")
		(21 "Eco1.User" user "User.Eco1")
		(23 "Eco2.User" user "User.Eco2")
		(25 "Edge.Cuts" user "Board Geometry/Outline")
		(27 "Margin" user)
		(31 "F.CrtYd" user "Package Geometry/Place Bound Top")
		(29 "B.CrtYd" user "Package Geometry/Place Bound Bottom")
		(35 "F.Fab" user "Ref Des/Assembly Top")
		(33 "B.Fab" user "Ref Des/Assembly Bottom")
	)
	(footprint ""
		(layer "F.Cu")
		(at 136.50468 -28.48102 90)
		(property "Reference" "R6196"
			(at 0 0 90)
			(layer "F.SilkS")
			(hide yes)
			(effects
				(font
					(size 1.27 1.27)
				)
			)
		)
		(property "Value" ""
			(at 0 0 90)
			(layer "F.Fab")
			(effects
				(font
					(size 1.27 1.27)
				)
			)
		)
		(duplicate_pad_numbers_are_jumpers no)
		(fp_line
			(start 0.32512 -0.175006)
			(end 0.32512 0.175006)
			(stroke
				(width 0.1)
				(type default)
			)
			(layer "F.Fab")
		)
		(fp_line
			(start -0.32512 -0.175006)
			(end 0.32512 -0.175006)
			(stroke
				(width 0.1)
				(type default)
			)
			(layer "F.Fab")
		)
		(fp_line
			(start 0.32512 0.175006)
			(end -0.32512 0.175006)
			(stroke
				(width 0.1)
				(type default)
			)
			(layer "F.Fab")
		)
		(fp_line
			(start -0.32512 0.175006)
			(end -0.32512 -0.175006)
			(stroke
				(width 0.1)
				(type default)
			)
			(layer "F.Fab")
		)
		(pad "1" smd rect
			(at -0.2667 0 90)
			(size 0.3048 0.381)
			(layers "F.Cu" "F.Mask" "F.Paste")
			(net "USB2_CPU0_P0_HUB2_R_DP")
		)
		(pad "2" smd rect
			(at 0.2667 0 270)
			(size 0.3048 0.381)
			(layers "F.Cu" "F.Mask" "F.Paste")
			(net "USB2_HUB_EXT_DP")
		)
	)
)
